(kicad_pcb
	(version 20260206)
	(generator "pcbnew")
	(generator_version "10.0")
	(general
		(thickness 1.6)
		(legacy_teardrops no)
	)
	(paper "A4")
	(title_block
		(title "Bryce Canyon_F.DPB_16315-1-OCP.brd")
		(comment 1 "Bryce Canyon / footprints 1785-1791 of 2223")
	)
	(layers
		(0 "F.Cu" signal "TOP")
		(4 "In1.Cu" signal "L2GND")
		(6 "In2.Cu" signal "L3")
		(8 "In3.Cu" signal "L4GND")
		(10 "In4.Cu" signal "L5")
		(12 "In5.Cu" signal "L6VCC")
		(14 "In6.Cu" signal "L7VCC")
		(16 "In7.Cu" signal "L8")
		(18 "In8.Cu" signal "L9GND")
		(20 "In9.Cu" signal "L10")
		(22 "In10.Cu" signal "L11GND")
		(2 "B.Cu" signal "BOTTOM")
		(9 "F.Adhes" user "F.Adhesive")
		(11 "B.Adhes" user "B.Adhesive")
		(13 "F.Paste" user "Package Geometry/Pastemask Top")
		(15 "B.Paste" user "Package Geometry/Pastemask Bottom")
		(5 "F.SilkS" user "Ref Des/Silkscreen Top")
		(7 "B.SilkS" user "Ref Des/Silkscreen Bottom")
		(1 "F.Mask" user "Board Geometry/Soldermask Top")
		(3 "B.Mask" user "Board Geometry/Soldermask Bottom")
		(17 "Dwgs.User" user "User.Drawings")
		(19 "Cmts.User" user "User.Comments")
		(21 "Eco1.User" user "User.Eco1")
		(23 "Eco2.User" user "User.Eco2")
		(25 "Edge.Cuts" user "Board Geometry/Outline")
		(27 "Margin" user)
		(31 "F.CrtYd" user "Package Geometry/Place Bound Top")
		(29 "B.CrtYd" user "Package Geometry/Place Bound Bottom")
		(35 "F.Fab" user "Ref Des/Assembly Top")
		(33 "B.Fab" user "Ref Des/Assembly Bottom")
	)
	(footprint ""
		(layer "F.Cu")
		(at 77.942948 -174.857918)
		(property "Reference" "Q86"
			(at 0 0 0)
			(layer "F.SilkS")
			(hide yes)
			(effects
				(font
					(size 1.27 1.27)
				)
			)
		)
		(property "Value" "AO4407AL-GP"
			(at -3.707384 -1.5367 0)
			(unlocked yes)
			(layer "F.Fab")
			(hide yes)
			(effects
				(font
					(size 1.016 1.016)
					(thickness 0.1524)
				)
			)
		)
		(property "Device Type" "SOIC8H69"
			(at -3.707384 -3.0607 0)
			(unlocked yes)
			(layer "F.Fab")
			(hide yes)
			(effects
				(font
					(size 1.016 1.016)
					(thickness 0.1524)
				)
			)
		)
		(duplicate_pad_numbers_are_jumpers no)
		(fp_line
			(start -2.7432 -1.4224)
			(end -2.7432 1.4224)
			(stroke
				(width 0.1524)
				(type default)
			)
			(layer "F.SilkS")
		)
		(fp_line
			(start -2.7432 1.4224)
			(end -2.6416 1.4224)
			(stroke
				(width 0.1524)
				(type default)
			)
			(layer "F.SilkS")
		)
		(fp_line
			(start -2.7432 1.4224)
			(end 2.1336 1.4224)
			(stroke
				(width 0.1524)
				(type default)
			)
			(layer "F.SilkS")
		)
		(fp_line
			(start -2.7178 -0.508)
			(end -2.1844 -0.0508)
			(stroke
				(width 0.1524)
				(type default)
			)
			(layer "F.SilkS")
		)
		(fp_line
			(start -2.6289 3.4417)
			(end -2.6289 1.4732)
			(stroke
				(width 0.381)
				(type default)
			)
			(layer "F.SilkS")
		)
		(fp_line
			(start -2.1844 -0.0508)
			(end -2.7178 0.508)
			(stroke
				(width 0.1524)
				(type default)
			)
			(layer "F.SilkS")
		)
		(fp_line
			(start 2.1336 -1.4224)
			(end -2.7432 -1.4224)
			(stroke
				(width 0.1524)
				(type default)
			)
			(layer "F.SilkS")
		)
		(fp_line
			(start 2.1336 1.4224)
			(end 2.1336 -1.4224)
			(stroke
				(width 0.1524)
				(type default)
			)
			(layer "F.SilkS")
		)
		(fp_poly
			(pts
				(xy -2.2098 -1.4224) (xy -2.2098 1.4224) (xy 2.2098 1.4224) (xy 2.2098 -1.4224)
			)
			(stroke
				(width 0)
				(type default)
			)
			(fill yes)
			(layer "F.SilkS")
		)
		(fp_rect
			(start -2.450084 2.999994)
			(end 2.450084 -2.999994)
			(stroke
				(width 0)
				(type default)
			)
			(fill no)
			(layer "F.CrtYd")
		)
		(fp_poly
			(pts
				(xy -2.8194 3.6322) (xy -2.8194 -3.6322) (xy 2.8194 -3.6322) (xy 2.8194 1.18364) (xy 2.450084 1.18364)
				(xy 2.450084 -2.999994) (xy -2.450084 -2.999994) (xy -2.450084 2.999994) (xy 2.450084 2.999994)
				(xy 2.450084 1.18618) (xy 2.8194 1.18618) (xy 2.8194 3.6322)
			)
			(stroke
				(width 0)
				(type default)
			)
			(fill no)
			(layer "F.CrtYd")
		)
		(fp_rect
			(start -2.8194 3.6322)
			(end 2.8194 -3.6322)
			(stroke
				(width 0)
				(type default)
			)
			(fill no)
			(layer "F.Fab")
		)
		(pad "1" smd rect
			(at -1.905 2.54)
			(size 0.635 1.651)
			(layers "F.Cu" "F.Mask" "F.Paste")
			(net "P12V_A")
		)
		(pad "2" smd rect
			(at -0.635 2.54)
			(size 0.635 1.651)
			(layers "F.Cu" "F.Mask" "F.Paste")
			(net "P12V_A")
		)
		(pad "3" smd rect
			(at 0.635 2.54)
			(size 0.635 1.651)
			(layers "F.Cu" "F.Mask" "F.Paste")
			(net "P12V_A")
		)
		(pad "4" smd rect
			(at 1.905 2.54)
			(size 0.635 1.651)
			(layers "F.Cu" "F.Mask" "F.Paste")
			(net "SW_HDD_N14")
		)
		(pad "5" smd rect
			(at 1.905 -2.54)
			(size 0.635 1.651)
			(layers "F.Cu" "F.Mask" "F.Paste")
			(net "P12V_HDD14")
		)
		(pad "6" smd rect
			(at 0.635 -2.54)
			(size 0.635 1.651)
			(layers "F.Cu" "F.Mask" "F.Paste")
			(net "P12V_HDD14")
		)
		(pad "7" smd rect
			(at -0.635 -2.54)
			(size 0.635 1.651)
			(layers "F.Cu" "F.Mask" "F.Paste")
			(net "P12V_HDD14")
		)
		(pad "8" smd rect
			(at -1.905 -2.54)
			(size 0.635 1.651)
			(layers "F.Cu" "F.Mask" "F.Paste")
			(net "P12V_HDD14")
		)
	)
	(footprint ""
		(layer "F.Cu")
		(at 221.402402 -377.73991 -90)
		(property "Reference" "C536"
			(at 0 0 270)
			(layer "F.SilkS")
			(hide yes)
			(effects
				(font
					(size 1.27 1.27)
				)
			)
		)
		(property "Value" "SCD1U16V2KX-3GP"
			(at 1.1811 -2.7051 270)
			(unlocked yes)
			(layer "F.Fab")
			(hide yes)
			(effects
				(font
					(size 1.016 1.016)
					(thickness 0.1524)
				)
			)
		)
		(property "Device Type" "C402H22"
			(at 1.1811 -4.2291 270)
			(unlocked yes)
			(layer "F.Fab")
			(hide yes)
			(effects
				(font
					(size 1.016 1.016)
					(thickness 0.1524)
				)
			)
		)
		(duplicate_pad_numbers_are_jumpers no)
		(fp_rect
			(start -0.4318 0.9525)
			(end 0.4318 -0.9525)
			(stroke
				(width 0)
				(type default)
			)
			(fill no)
			(layer "F.CrtYd")
		)
		(fp_rect
			(start -0.4318 0.9525)
			(end 0.4318 -0.9525)
			(stroke
				(width 0)
				(type default)
			)
			(fill no)
			(layer "F.Fab")
		)
		(pad "1" smd custom
			(at 0 -0.4445 270)
			(size 0.1524 0.1524)
			(layers "F.Cu" "F.Mask" "F.Paste")
			(net "P3V3_STBY_B")
			(options
				(clearance outline)
				(anchor circle)
			)
			(primitives
				(gr_poly
					(pts
						(arc
							(start 0.3048 -0.2032)
							(mid 0.275042 -0.275042)
							(end 0.2032 -0.3048)
						)
						(arc
							(start -0.2032 -0.3048)
							(mid -0.275042 -0.275042)
							(end -0.3048 -0.2032)
						)
						(arc
							(start -0.3048 0.2032)
							(mid -0.275042 0.275042)
							(end -0.2032 0.3048)
						)
						(arc
							(start 0.2032 0.3048)
							(mid 0.275042 0.275042)
							(end 0.3048 0.2032)
						)
					)
					(width 0)
					(fill yes)
				)
			)
		)
		(pad "2" smd custom
			(at 0 0.4445 270)
			(size 0.1524 0.1524)
			(layers "F.Cu" "F.Mask" "F.Paste")
			(net "GND")
			(options
				(clearance outline)
				(anchor circle)
			)
			(primitives
				(gr_poly
					(pts
						(arc
							(start 0.3048 -0.2032)
							(mid 0.275042 -0.275042)
							(end 0.2032 -0.3048)
						)
						(arc
							(start -0.2032 -0.3048)
							(mid -0.275042 -0.275042)
							(end -0.3048 -0.2032)
						)
						(arc
							(start -0.3048 0.2032)
							(mid -0.275042 0.275042)
							(end -0.2032 0.3048)
						)
						(arc
							(start 0.2032 0.3048)
							(mid 0.275042 0.275042)
							(end 0.3048 0.2032)
						)
					)
					(width 0)
					(fill yes)
				)
			)
		)
	)
	(footprint ""
		(layer "F.Cu")
		(at 83.530948 -278.554942 180)
		(property "Reference" "Q13"
			(at 0 0 180)
			(layer "F.SilkS")
			(hide yes)
			(effects
				(font
					(size 1.27 1.27)
				)
			)
		)
		(property "Value" "2N7002KDW-GP"
			(at -2.3622 -8.2042 180)
			(unlocked yes)
			(layer "F.Fab")
			(hide yes)
			(effects
				(font
					(size 1.016 1.016)
					(thickness 0.1524)
				)
			)
		)
		(property "Device Type" "SOT-363H44"
			(at -2.3622 -10.1092 180)
			(unlocked yes)
			(layer "F.Fab")
			(hide yes)
			(effects
				(font
					(size 1.016 1.016)
					(thickness 0.1524)
				)
			)
		)
		(duplicate_pad_numbers_are_jumpers no)
		(fp_line
			(start 1.4478 1.7018)
			(end 1.4478 -1.7018)
			(stroke
				(width 0.1524)
				(type default)
			)
			(layer "F.SilkS")
		)
		(fp_line
			(start 1.4478 -1.7018)
			(end -1.4478 -1.7018)
			(stroke
				(width 0.1524)
				(type default)
			)
			(layer "F.SilkS")
		)
		(fp_line
			(start -1.27 1.524)
			(end -1.27 0.6604)
			(stroke
				(width 0.4826)
				(type default)
			)
			(layer "F.SilkS")
		)
		(fp_line
			(start -1.4478 1.7018)
			(end 1.4478 1.7018)
			(stroke
				(width 0.1524)
				(type default)
			)
			(layer "F.SilkS")
		)
		(fp_line
			(start -1.4478 -1.7018)
			(end -1.4478 1.7018)
			(stroke
				(width 0.1524)
				(type default)
			)
			(layer "F.SilkS")
		)
		(fp_poly
			(pts
				(xy -1.524 -1.778) (xy 1.524 -1.778) (xy 1.524 1.778) (xy -1.524 1.778)
			)
			(stroke
				(width 0)
				(type default)
			)
			(fill no)
			(layer "F.CrtYd")
		)
		(fp_poly
			(pts
				(xy -1.524 -1.778) (xy 1.524 -1.778) (xy 1.524 1.778) (xy -1.524 1.778)
			)
			(stroke
				(width 0)
				(type default)
			)
			(fill no)
			(layer "F.Fab")
		)
		(pad "1" smd rect
			(at -0.65024 0.9398 180)
			(size 0.4064 1.016)
			(layers "F.Cu" "F.Mask" "F.Paste")
			(net "GND")
		)
		(pad "2" smd rect
			(at 0 0.9398 180)
			(size 0.4064 1.016)
			(layers "F.Cu" "F.Mask" "F.Paste")
			(net "SW_PWR_R_HDD2")
		)
		(pad "3" smd rect
			(at 0.65024 0.9398 180)
			(size 0.4064 1.016)
			(layers "F.Cu" "F.Mask" "F.Paste")
			(net "SW_HDD_P2")
		)
		(pad "4" smd rect
			(at 0.65024 -0.9398 180)
			(size 0.4064 1.016)
			(layers "F.Cu" "F.Mask" "F.Paste")
			(net "GND")
		)
		(pad "5" smd rect
			(at 0 -0.9398 180)
			(size 0.4064 1.016)
			(layers "F.Cu" "F.Mask" "F.Paste")
			(net "SW_HDD_G2")
		)
		(pad "6" smd rect
			(at -0.65024 -0.9398 180)
			(size 0.4064 1.016)
			(layers "F.Cu" "F.Mask" "F.Paste")
			(net "SW_HDD_R2")
		)
	)
	(footprint ""
		(layer "F.Cu")
		(at 222.921322 -137.77087 -90)
		(property "Reference" "R1002"
			(at 0 0 270)
			(layer "F.SilkS")
			(hide yes)
			(effects
				(font
					(size 1.27 1.27)
				)
			)
		)
		(property "Value" "100KR2F-L1-GP"
			(at 0.064008 -3.993896 270)
			(unlocked yes)
			(layer "F.Fab")
			(hide yes)
			(effects
				(font
					(size 1.016 1.016)
					(thickness 0.1524)
				)
			)
		)
		(property "Device Type" "R402H16"
			(at 0.064008 -5.517896 270)
			(unlocked yes)
			(layer "F.Fab")
			(hide yes)
			(effects
				(font
					(size 1.016 1.016)
					(thickness 0.1524)
				)
			)
		)
		(duplicate_pad_numbers_are_jumpers no)
		(fp_line
			(start -0.508 -0.9398)
			(end -0.508 0.9398)
			(stroke
				(width 0.1524)
				(type default)
			)
			(layer "F.SilkS")
		)
		(fp_line
			(start 0.508 -0.9398)
			(end -0.508 -0.9398)
			(stroke
				(width 0.1524)
				(type default)
			)
			(layer "F.SilkS")
		)
		(fp_rect
			(start -0.508 0.9398)
			(end 0.508 -0.9398)
			(stroke
				(width 0)
				(type default)
			)
			(fill no)
			(layer "F.CrtYd")
		)
		(fp_rect
			(start -0.508 0.9398)
			(end 0.508 -0.9398)
			(stroke
				(width 0)
				(type default)
			)
			(fill no)
			(layer "F.Fab")
		)
		(pad "1" smd custom
			(at 0 -0.4445 270)
			(size 0.1397 0.1397)
			(layers "F.Cu" "F.Mask" "F.Paste")
			(net "PCIE_COMP_A_PCIE_RST_1")
			(options
				(clearance outline)
				(anchor circle)
			)
			(primitives
				(gr_poly
					(pts
						(arc
							(start -0.1778 -0.2794)
							(mid -0.249642 -0.249642)
							(end -0.2794 -0.1778)
						)
						(arc
							(start -0.2794 0.1778)
							(mid -0.249642 0.249642)
							(end -0.1778 0.2794)
						)
						(arc
							(start 0.1778 0.2794)
							(mid 0.249642 0.249642)
							(end 0.2794 0.1778)
						)
						(arc
							(start 0.2794 -0.1778)
							(mid 0.249642 -0.249642)
							(end 0.1778 -0.2794)
						)
					)
					(width 0)
					(fill yes)
				)
			)
		)
		(pad "2" smd custom
			(at 0 0.4445 270)
			(size 0.1397 0.1397)
			(layers "F.Cu" "F.Mask" "F.Paste")
			(net "GND")
			(options
				(clearance outline)
				(anchor circle)
			)
			(primitives
				(gr_poly
					(pts
						(arc
							(start -0.1778 -0.2794)
							(mid -0.249642 -0.249642)
							(end -0.2794 -0.1778)
						)
						(arc
							(start -0.2794 0.1778)
							(mid -0.249642 0.249642)
							(end -0.1778 0.2794)
						)
						(arc
							(start 0.1778 0.2794)
							(mid 0.249642 0.249642)
							(end 0.2794 0.1778)
						)
						(arc
							(start 0.2794 -0.1778)
							(mid 0.249642 -0.249642)
							(end 0.1778 -0.2794)
						)
					)
					(width 0)
					(fill yes)
				)
			)
		)
	)
	(footprint ""
		(layer "F.Cu")
		(at 467.499954 -269.999968)
		(property "Reference" ""
			(at 0 0 0)
			(layer "F.SilkS")
			(hide yes)
			(effects
				(font
					(size 1.27 1.27)
				)
			)
		)
		(property "Value" "*"
			(at -6.3373 -0.4572 0)
			(unlocked yes)
			(layer "F.Fab")
			(hide yes)
			(effects
				(font
					(size 1.016 1.016)
					(thickness 0.1524)
				)
			)
		)
		(duplicate_pad_numbers_are_jumpers no)
		(fp_poly
			(pts
				(arc
					(start 5.0673 0)
					(mid -5.0673 0)
					(end 5.0673 0)
				)
			)
			(stroke
				(width 0)
				(type default)
			)
			(fill no)
			(layer "B.CrtYd")
		)
		(fp_poly
			(pts
				(arc
					(start 5.0673 0)
					(mid -5.0673 0)
					(end 5.0673 0)
				)
			)
			(stroke
				(width 0)
				(type default)
			)
			(fill no)
			(layer "F.CrtYd")
		)
		(fp_poly
			(pts
				(arc
					(start 5.0673 0)
					(mid -5.0673 0)
					(end 5.0673 0)
				)
			)
			(stroke
				(width 0)
				(type default)
			)
			(fill no)
			(layer "B.Fab")
		)
		(fp_poly
			(pts
				(arc
					(start 5.0673 0)
					(mid -5.0673 0)
					(end 5.0673 0)
				)
			)
			(stroke
				(width 0)
				(type default)
			)
			(fill no)
			(layer "F.Fab")
		)
		(pad "1" thru_hole circle
			(at 0 0)
			(size 9.525 9.525)
			(drill 3.556)
			(layers "*.Cu" "*.Mask")
			(remove_unused_layers no)
			(net "Net_95")
			(clearance -2.4765)
			(thermal_gap 0.3048)
			(padstack
				(mode front_inner_back)
				(layer "Inner"
					(shape circle)
					(size 3.9624 3.9624)
					(clearance 0.3048)
				)
				(layer "B.Cu"
					(shape circle)
					(size 9.525 9.525)
					(clearance -2.4765)
				)
			)
		)
		(zone
			(layers "F.Cu" "B.Cu" "In1.Cu" "In2.Cu" "In3.Cu" "In4.Cu" "In5.Cu" "In6.Cu"
				"In7.Cu" "In8.Cu" "In9.Cu" "In10.Cu"
			)
			(hatch none 0.5)
			(connect_pads
				(clearance 0)
			)
			(min_thickness 0.25)
			(keepout
				(tracks not_allowed)
				(vias allowed)
				(pads allowed)
				(copperpour not_allowed)
				(footprints allowed)
			)
			(placement
				(enabled no)
				(sheetname "")
			)
			(fill
				(thermal_gap 0.5)
				(thermal_bridge_width 0.5)
				(island_removal_mode 0)
			)
			(polygon
				(pts
					(arc
						(start 472.262454 -269.999968)
						(mid 462.737454 -269.999968)
						(end 472.262454 -269.999968)
					)
				)
			)
		)
	)
	(footprint ""
		(layer "F.Cu")
		(at 335.788 -157.585918 180)
		(property "Reference" "R555"
			(at 0 0 180)
			(layer "F.SilkS")
			(hide yes)
			(effects
				(font
					(size 1.27 1.27)
				)
			)
		)
		(property "Value" "0R2J-2-GP"
			(at 0.064008 -3.993896 180)
			(unlocked yes)
			(layer "F.Fab")
			(hide yes)
			(effects
				(font
					(size 1.016 1.016)
					(thickness 0.1524)
				)
			)
		)
		(property "Device Type" "R402H16"
			(at 0.064008 -5.517896 180)
			(unlocked yes)
			(layer "F.Fab")
			(hide yes)
			(effects
				(font
					(size 1.016 1.016)
					(thickness 0.1524)
				)
			)
		)
		(duplicate_pad_numbers_are_jumpers no)
		(fp_line
			(start 0.508 -0.9398)
			(end -0.508 -0.9398)
			(stroke
				(width 0.1524)
				(type default)
			)
			(layer "F.SilkS")
		)
		(fp_line
			(start -0.508 -0.9398)
			(end -0.508 0.9398)
			(stroke
				(width 0.1524)
				(type default)
			)
			(layer "F.SilkS")
		)
		(fp_rect
			(start -0.508 0.9398)
			(end 0.508 -0.9398)
			(stroke
				(width 0)
				(type default)
			)
			(fill no)
			(layer "F.CrtYd")
		)
		(fp_rect
			(start -0.508 0.9398)
			(end 0.508 -0.9398)
			(stroke
				(width 0)
				(type default)
			)
			(fill no)
			(layer "F.Fab")
		)
		(pad "1" smd custom
			(at 0 -0.4445 180)
			(size 0.1397 0.1397)
			(layers "F.Cu" "F.Mask" "F.Paste")
			(net "DRIVE_A_18_PWR")
			(options
				(clearance outline)
				(anchor circle)
			)
			(primitives
				(gr_poly
					(pts
						(arc
							(start -0.1778 -0.2794)
							(mid -0.249642 -0.249642)
							(end -0.2794 -0.1778)
						)
						(arc
							(start -0.2794 0.1778)
							(mid -0.249642 0.249642)
							(end -0.1778 0.2794)
						)
						(arc
							(start 0.1778 0.2794)
							(mid 0.249642 0.249642)
							(end 0.2794 0.1778)
						)
						(arc
							(start 0.2794 -0.1778)
							(mid 0.249642 -0.249642)
							(end 0.1778 -0.2794)
						)
					)
					(width 0)
					(fill yes)
				)
			)
		)
		(pad "2" smd custom
			(at 0 0.4445 180)
			(size 0.1397 0.1397)
			(layers "F.Cu" "F.Mask" "F.Paste")
			(net "SW_PWR_R_HDD18")
			(options
				(clearance outline)
				(anchor circle)
			)
			(primitives
				(gr_poly
					(pts
						(arc
							(start -0.1778 -0.2794)
							(mid -0.249642 -0.249642)
							(end -0.2794 -0.1778)
						)
						(arc
							(start -0.2794 0.1778)
							(mid -0.249642 0.249642)
							(end -0.1778 0.2794)
						)
						(arc
							(start 0.1778 0.2794)
							(mid 0.249642 0.249642)
							(end 0.2794 0.1778)
						)
						(arc
							(start 0.2794 -0.1778)
							(mid 0.249642 -0.249642)
							(end 0.1778 -0.2794)
						)
					)
					(width 0)
					(fill yes)
				)
			)
		)
	)
	(footprint ""
		(layer "F.Cu")
		(at 176.165002 -242.25377)
		(property "Reference" "R227"
			(at 0 0 0)
			(layer "F.SilkS")
			(hide yes)
			(effects
				(font
					(size 1.27 1.27)
				)
			)
		)
		(property "Value" "91R3F-1-GP"
			(at -0.0254 -2.5146 0)
			(unlocked yes)
			(layer "F.Fab")
			(hide yes)
			(effects
				(font
					(size 1.016 1.016)
					(thickness 0.1524)
				)
			)
		)
		(property "Device Type" "R603H22"
			(at -0.0254 -4.0386 0)
			(unlocked yes)
			(layer "F.Fab")
			(hide yes)
			(effects
				(font
					(size 1.016 1.016)
					(thickness 0.1524)
				)
			)
		)
		(duplicate_pad_numbers_are_jumpers no)
		(fp_line
			(start -0.4826 0)
			(end -0.2032 0)
			(stroke
				(width 0.2032)
				(type default)
			)
			(layer "F.SilkS")
		)
		(fp_line
			(start 0.2032 0)
			(end 0.4826 0)
			(stroke
				(width 0.2032)
				(type default)
			)
			(layer "F.SilkS")
		)
		(fp_rect
			(start -0.5842 1.3335)
			(end 0.5842 -1.3335)
			(stroke
				(width 0)
				(type default)
			)
			(fill no)
			(layer "F.CrtYd")
		)
		(fp_rect
			(start -0.5842 1.3335)
			(end 0.5842 -1.3335)
			(stroke
				(width 0)
				(type default)
			)
			(fill no)
			(layer "F.Fab")
		)
		(pad "1" smd custom
			(at 0 -0.762)
			(size 0.2159 0.2159)
			(layers "F.Cu" "F.Mask" "F.Paste")
			(net "P5V_A_1")
			(options
				(clearance outline)
				(anchor circle)
			)
			(primitives
				(gr_poly
					(pts
						(arc
							(start -0.3302 -0.4318)
							(mid -0.402042 -0.402042)
							(end -0.4318 -0.3302)
						)
						(arc
							(start -0.4318 0.3302)
							(mid -0.402042 0.402042)
							(end -0.3302 0.4318)
						)
						(arc
							(start 0.3302 0.4318)
							(mid 0.402042 0.402042)
							(end 0.4318 0.3302)
						)
						(arc
							(start 0.4318 -0.3302)
							(mid 0.402042 -0.402042)
							(end 0.3302 -0.4318)
						)
					)
					(width 0)
					(fill yes)
				)
			)
		)
		(pad "2" smd custom
			(at 0 0.762)
			(size 0.2159 0.2159)
			(layers "F.Cu" "F.Mask" "F.Paste")
			(net "DRV_ACT_5")
			(options
				(clearance outline)
				(anchor circle)
			)
			(primitives
				(gr_poly
					(pts
						(arc
							(start -0.3302 -0.4318)
							(mid -0.402042 -0.402042)
							(end -0.4318 -0.3302)
						)
						(arc
							(start -0.4318 0.3302)
							(mid -0.402042 0.402042)
							(end -0.3302 0.4318)
						)
						(arc
							(start 0.3302 0.4318)
							(mid 0.402042 0.402042)
							(end 0.4318 0.3302)
						)
						(arc
							(start 0.4318 -0.3302)
							(mid 0.402042 -0.402042)
							(end 0.3302 -0.4318)
						)
					)
					(width 0)
					(fill yes)
				)
			)
		)
	)
)
